#ISCELL
  pure_quanta quanta_title_block_c *
  *
#CELL
  pure_quanta q_cap *
  page70_i1
#CELL
  pure_quanta q_cap *
  page70_i10
#CELL
  pure_quanta q_cap *
  page70_i11
#CELL
  pure_quanta q_cap *
  page70_i12
#CELL
  pure_quanta q_cap *
  page70_i13
#CELL
  pure_quanta q_cap *
  page70_i14
#CELL
  pure_quanta q_cap *
  page70_i15
#CELL
  pure_quanta q_cap *
  page70_i16
#ISCELL
  pure_quanta_power universal_gnd *
  page70_i17
#CELL
  pure_quanta q_cap *
  page70_i18
#ISCELL
  pure_quanta_power universal_power *
  page70_i2
#ISCELL
  pure_quanta_power universal_power *
  page70_i23
#ISCELL
  pure_quanta_power universal_gnd *
  page70_i24
#CELL
  pure_quanta q_cap *
  page70_i25
#CELL
  pure_quanta q_cap *
  page70_i26
#CELL
  pure_quanta q_cap *
  page70_i3
#ISCELL
  pure_quanta_power universal_power *
  page70_i4
#ISCELL
  pure_quanta_power universal_gnd *
  page70_i7
#CELL
  pure_quanta q_cap *
  page70_i8
#CELL
  pure_quanta q_cap *
  page70_i9
